FILE_TYPE=LIBRARY_PARTS;
primitive '74LVC1G126SE7';
  pin
    'A':
      PIN_NUMBER='(2)';
      INPUT_LOAD='(-0.01,0.01)';
    'Y':
      PIN_NUMBER='(4)';
      OUTPUT_LOAD='(1.0,-1.0)';
    'VCC':
      PIN_NUMBER='(5)';
      PINUSE='POWER';
      NO_LOAD_CHECK='Both';
      NO_IO_CHECK='Both';
      NO_ASSERT_CHECK='TRUE';
      NO_DIR_CHECK='TRUE';
      ALLOW_CONNECT='TRUE';
    'GND':
      PIN_NUMBER='(3)';
      PINUSE='POWER';
      NO_LOAD_CHECK='Both';
      NO_IO_CHECK='Both';
      NO_ASSERT_CHECK='TRUE';
      NO_DIR_CHECK='TRUE';
      ALLOW_CONNECT='TRUE';
    'OE':
      PIN_NUMBER='(1)';
      INPUT_LOAD='(-0.01,0.01)';
  end_pin;
  body
    PART_NAME='74LVC1G126SE7';
    BODY_NAME='74LVC1G126SE7';
    PHYS_DES_PREFIX='U';
    CLASS='IC';
  end_body;
end_primitive;

END.
